# S9S_MB_2U (Grand Teton) — schematic netlist excerpt (pin names and nets, part order shuffled) for the footprints in the layout excerpt that follows; sources: Cadence DE-HDL packaged netlist, KiCad conversion of 03242023_DA0F0TMBIJ0_F0T_Motherboard_J_brd_V01_OCP.brd

PC257  Q_CAP  100NF 50V 10% X7R  pkg C0402  page 269 : A = SW_PVCCIN_CPU0_BOOT5_R ; B = SW_PVCCIN_CPU0_BOOTR5
C959  Q_CAP_DIFFBUS  DIFF BUS_0.22UF 6.3V 20% X6S  pkg C0201  page 173 : \1\ = P5E_CPU0_PE2_TX_C_DP<3> ; \2\ = P5E_CPU0_PE2_TX_DP<3>
R4600  Q_RES  0 5% CHIP  pkg 0402LF  page 214 : A = HP_LVC3_OCP_V3_1_P12V_PWRGD ; B = HP_LVC3_OCP_V3_1_HSC_PWRGD_PLD_

(kicad_pcb
	(version 20260206)
	(generator "pcbnew")
	(generator_version "10.0")
	(general
		(thickness 1.6)
		(legacy_teardrops no)
	)
	(paper "A4")
	(title_block
		(title "03242023_DA0F0TMBIJ0_F0T_Motherboard_J_brd_V01_OCP.brd")
		(comment 1 "Grand Teton / footprints 2493-2495 of 6105")
	)
	(layers
		(0 "F.Cu" signal "TOP")
		(4 "In1.Cu" signal "GND")
		(6 "In2.Cu" signal "IN1")
		(8 "In3.Cu" signal "GND1")
		(10 "In4.Cu" signal "IN2")
		(12 "In5.Cu" signal "GND2")
		(14 "In6.Cu" signal "IN3")
		(16 "In7.Cu" signal "GND3")
		(18 "In8.Cu" signal "VCC")
		(20 "In9.Cu" signal "VCC1")
		(22 "In10.Cu" signal "GND4")
		(24 "In11.Cu" signal "IN4")
		(26 "In12.Cu" signal "GND5")
		(28 "In13.Cu" signal "IN5")
		(30 "In14.Cu" signal "GND6")
		(32 "In15.Cu" signal "IN6")
		(34 "In16.Cu" signal "GND7")
		(2 "B.Cu" signal "BOTTOM")
		(9 "F.Adhes" user "F.Adhesive")
		(11 "B.Adhes" user "B.Adhesive")
		(13 "F.Paste" user "Package Geometry/Pastemask Top")
		(15 "B.Paste" user "Package Geometry/Pastemask Bottom")
		(5 "F.SilkS" user "Ref Des/Silkscreen Top")
		(7 "B.SilkS" user "Ref Des/Silkscreen Bottom")
		(1 "F.Mask" user "Board Geometry/Soldermask Top")
		(3 "B.Mask" user "Board Geometry/Soldermask Bottom")
		(17 "Dwgs.User" user "User.Drawings")
		(19 "Cmts.User" user "User.Comments")
		(21 "Eco1.User" user "User.Eco1")
		(23 "Eco2.User" user "User.Eco2")
		(25 "Edge.Cuts" user "Board Geometry/Outline")
		(27 "Margin" user)
		(31 "F.CrtYd" user "Package Geometry/Place Bound Top")
		(29 "B.CrtYd" user "Package Geometry/Place Bound Bottom")
		(35 "F.Fab" user "Ref Des/Assembly Top")
		(33 "B.Fab" user "Ref Des/Assembly Bottom")
	)
	(footprint ""
		(layer "F.Cu")
		(at 379.36551 -341.729822 -90)
		(property "Reference" "PC257"
			(at 0 0 270)
			(layer "F.SilkS")
			(hide yes)
			(effects
				(font
					(size 1.27 1.27)
				)
			)
		)
		(property "Value" ""
			(at 0 0 270)
			(layer "F.Fab")
			(effects
				(font
					(size 1.27 1.27)
				)
			)
		)
		(duplicate_pad_numbers_are_jumpers no)
		(fp_line
			(start -0.7874 0.4064)
			(end -0.7874 -0.4064)
			(stroke
				(width 0.1524)
				(type default)
			)
			(layer "F.SilkS")
		)
		(fp_line
			(start 0.7874 0.4064)
			(end -0.7874 0.4064)
			(stroke
				(width 0.1524)
				(type default)
			)
			(layer "F.SilkS")
		)
		(fp_line
			(start -0.7874 -0.4064)
			(end 0.7874 -0.4064)
			(stroke
				(width 0.1524)
				(type default)
			)
			(layer "F.SilkS")
		)
		(fp_line
			(start 0.7874 -0.4064)
			(end 0.7874 0.4064)
			(stroke
				(width 0.1524)
				(type default)
			)
			(layer "F.SilkS")
		)
		(fp_line
			(start -0.67945 0.3048)
			(end -0.67945 -0.305054)
			(stroke
				(width 0.1)
				(type default)
			)
			(layer "F.Fab")
		)
		(fp_line
			(start -0.12065 0.3048)
			(end -0.67945 0.3048)
			(stroke
				(width 0.1)
				(type default)
			)
			(layer "F.Fab")
		)
		(fp_line
			(start 0.120396 0.3048)
			(end 0.120396 0.2794)
			(stroke
				(width 0.1)
				(type default)
			)
			(layer "F.Fab")
		)
		(fp_line
			(start 0.67945 0.3048)
			(end 0.120396 0.3048)
			(stroke
				(width 0.1)
				(type default)
			)
			(layer "F.Fab")
		)
		(fp_line
			(start -0.12065 0.2794)
			(end -0.12065 0.3048)
			(stroke
				(width 0.1)
				(type default)
			)
			(layer "F.Fab")
		)
		(fp_line
			(start 0.120396 0.2794)
			(end -0.12065 0.2794)
			(stroke
				(width 0.1)
				(type default)
			)
			(layer "F.Fab")
		)
		(fp_line
			(start -0.12065 -0.2794)
			(end 0.12065 -0.2794)
			(stroke
				(width 0.1)
				(type default)
			)
			(layer "F.Fab")
		)
		(fp_line
			(start 0.12065 -0.2794)
			(end 0.12065 -0.3048)
			(stroke
				(width 0.1)
				(type default)
			)
			(layer "F.Fab")
		)
		(fp_line
			(start 0.12065 -0.3048)
			(end 0.67945 -0.3048)
			(stroke
				(width 0.1)
				(type default)
			)
			(layer "F.Fab")
		)
		(fp_line
			(start 0.67945 -0.3048)
			(end 0.67945 0.3048)
			(stroke
				(width 0.1)
				(type default)
			)
			(layer "F.Fab")
		)
		(fp_line
			(start -0.67945 -0.305054)
			(end -0.12065 -0.305054)
			(stroke
				(width 0.1)
				(type default)
			)
			(layer "F.Fab")
		)
		(fp_line
			(start -0.12065 -0.305054)
			(end -0.12065 -0.2794)
			(stroke
				(width 0.1)
				(type default)
			)
			(layer "F.Fab")
		)
		(pad "1" smd circle
			(at -0.40005 0 270)
			(size 0 0)
			(layers "F.Cu" "F.Mask" "F.Paste")
			(net "SW_PVCCIN_CPU0_BOOT5_R")
		)
		(pad "2" smd circle
			(at 0.40005 0 270)
			(size 0 0)
			(layers "F.Cu" "F.Mask" "F.Paste")
			(net "SW_PVCCIN_CPU0_BOOTR5")
		)
	)
	(footprint ""
		(layer "F.Cu")
		(at 408.15641 -402.371052 -90)
		(property "Reference" "C959"
			(at 0 0 270)
			(layer "F.SilkS")
			(hide yes)
			(effects
				(font
					(size 1.27 1.27)
				)
			)
		)
		(property "Value" ""
			(at 0 0 270)
			(layer "F.Fab")
			(effects
				(font
					(size 1.27 1.27)
				)
			)
		)
		(duplicate_pad_numbers_are_jumpers no)
		(fp_line
			(start -0.299974 0.150114)
			(end -0.299974 -0.150114)
			(stroke
				(width 0.1)
				(type default)
			)
			(layer "F.Fab")
		)
		(fp_line
			(start 0.299974 0.150114)
			(end -0.299974 0.150114)
			(stroke
				(width 0.1)
				(type default)
			)
			(layer "F.Fab")
		)
		(fp_line
			(start -0.299974 -0.150114)
			(end 0.299974 -0.150114)
			(stroke
				(width 0.1)
				(type default)
			)
			(layer "F.Fab")
		)
		(fp_line
			(start 0.299974 -0.150114)
			(end 0.299974 0.150114)
			(stroke
				(width 0.1)
				(type default)
			)
			(layer "F.Fab")
		)
		(pad "1" smd rect
			(at -0.2667 0 270)
			(size 0.3048 0.381)
			(layers "F.Cu" "F.Mask" "F.Paste")
			(net "P5E_CPU0_PE2_TX_C_DP<3>")
		)
		(pad "2" smd rect
			(at 0.2667 0 270)
			(size 0.3048 0.381)
			(layers "F.Cu" "F.Mask" "F.Paste")
			(net "P5E_CPU0_PE2_TX_DP<3>")
		)
	)
	(footprint ""
		(layer "F.Cu")
		(at 190.291466 -126.963678 -90)
		(property "Reference" "R4600"
			(at 0 0 270)
			(layer "F.SilkS")
			(hide yes)
			(effects
				(font
					(size 1.27 1.27)
				)
			)
		)
		(property "Value" ""
			(at 0 0 270)
			(layer "F.Fab")
			(effects
				(font
					(size 1.27 1.27)
				)
			)
		)
		(duplicate_pad_numbers_are_jumpers no)
		(fp_line
			(start -0.7874 0.4064)
			(end -0.7874 -0.4064)
			(stroke
				(width 0.1524)
				(type default)
			)
			(layer "F.SilkS")
		)
		(fp_line
			(start 0.7874 0.4064)
			(end -0.7874 0.4064)
			(stroke
				(width 0.1524)
				(type default)
			)
			(layer "F.SilkS")
		)
		(fp_line
			(start -0.7874 -0.4064)
			(end 0.7874 -0.4064)
			(stroke
				(width 0.1524)
				(type default)
			)
			(layer "F.SilkS")
		)
		(fp_line
			(start 0.7874 -0.4064)
			(end 0.7874 0.4064)
			(stroke
				(width 0.1524)
				(type default)
			)
			(layer "F.SilkS")
		)
		(fp_line
			(start -0.67945 0.3048)
			(end -0.67945 -0.305054)
			(stroke
				(width 0.1)
				(type default)
			)
			(layer "F.Fab")
		)
		(fp_line
			(start -0.12065 0.3048)
			(end -0.67945 0.3048)
			(stroke
				(width 0.1)
				(type default)
			)
			(layer "F.Fab")
		)
		(fp_line
			(start 0.120396 0.3048)
			(end 0.120396 0.2794)
			(stroke
				(width 0.1)
				(type default)
			)
			(layer "F.Fab")
		)
		(fp_line
			(start 0.67945 0.3048)
			(end 0.120396 0.3048)
			(stroke
				(width 0.1)
				(type default)
			)
			(layer "F.Fab")
		)
		(fp_line
			(start -0.12065 0.2794)
			(end -0.12065 0.3048)
			(stroke
				(width 0.1)
				(type default)
			)
			(layer "F.Fab")
		)
		(fp_line
			(start 0.120396 0.2794)
			(end -0.12065 0.2794)
			(stroke
				(width 0.1)
				(type default)
			)
			(layer "F.Fab")
		)
		(fp_line
			(start -0.12065 -0.2794)
			(end 0.12065 -0.2794)
			(stroke
				(width 0.1)
				(type default)
			)
			(layer "F.Fab")
		)
		(fp_line
			(start 0.12065 -0.2794)
			(end 0.12065 -0.3048)
			(stroke
				(width 0.1)
				(type default)
			)
			(layer "F.Fab")
		)
		(fp_line
			(start 0.12065 -0.3048)
			(end 0.67945 -0.3048)
			(stroke
				(width 0.1)
				(type default)
			)
			(layer "F.Fab")
		)
		(fp_line
			(start 0.67945 -0.3048)
			(end 0.67945 0.3048)
			(stroke
				(width 0.1)
				(type default)
			)
			(layer "F.Fab")
		)
		(fp_line
			(start -0.67945 -0.305054)
			(end -0.12065 -0.305054)
			(stroke
				(width 0.1)
				(type default)
			)
			(layer "F.Fab")
		)
		(fp_line
			(start -0.12065 -0.305054)
			(end -0.12065 -0.2794)
			(stroke
				(width 0.1)
				(type default)
			)
			(layer "F.Fab")
		)
		(pad "1" smd circle
			(at -0.40005 0 270)
			(size 0 0)
			(layers "F.Cu" "F.Mask" "F.Paste")
			(net "HP_LVC3_OCP_V3_1_P12V_PWRGD")
		)
		(pad "2" smd circle
			(at 0.40005 0 270)
			(size 0 0)
			(layers "F.Cu" "F.Mask" "F.Paste")
			(net "HP_LVC3_OCP_V3_1_HSC_PWRGD_PLD_")
		)
	)
)
